# S9S_MB_2U (Grand Teton) — schematic netlist excerpt (pin names and nets, part order shuffled) for the footprints in the layout excerpt that follows; sources: Cadence DE-HDL packaged netlist, KiCad conversion of 03242023_DA0F0TMBIJ0_F0T_Motherboard_J_brd_V01_OCP.brd

PC322  Q_CAPP  560UF 2.5V 20% OSCON  pkg THLF  page 267 : A = PVCCIN_CPU0 ; B = GND

(kicad_pcb
	(version 20260206)
	(generator "pcbnew")
	(generator_version "10.0")
	(general
		(thickness 1.6)
		(legacy_teardrops no)
	)
	(paper "A4")
	(title_block
		(title "03242023_DA0F0TMBIJ0_F0T_Motherboard_J_brd_V01_OCP.brd")
		(comment 1 "Grand Teton / footprints 1369-1369 of 6105")
	)
	(layers
		(0 "F.Cu" signal "TOP")
		(4 "In1.Cu" signal "GND")
		(6 "In2.Cu" signal "IN1")
		(8 "In3.Cu" signal "GND1")
		(10 "In4.Cu" signal "IN2")
		(12 "In5.Cu" signal "GND2")
		(14 "In6.Cu" signal "IN3")
		(16 "In7.Cu" signal "GND3")
		(18 "In8.Cu" signal "VCC")
		(20 "In9.Cu" signal "VCC1")
		(22 "In10.Cu" signal "GND4")
		(24 "In11.Cu" signal "IN4")
		(26 "In12.Cu" signal "GND5")
		(28 "In13.Cu" signal "IN5")
		(30 "In14.Cu" signal "GND6")
		(32 "In15.Cu" signal "IN6")
		(34 "In16.Cu" signal "GND7")
		(2 "B.Cu" signal "BOTTOM")
		(9 "F.Adhes" user "F.Adhesive")
		(11 "B.Adhes" user "B.Adhesive")
		(13 "F.Paste" user "Package Geometry/Pastemask Top")
		(15 "B.Paste" user "Package Geometry/Pastemask Bottom")
		(5 "F.SilkS" user "Ref Des/Silkscreen Top")
		(7 "B.SilkS" user "Ref Des/Silkscreen Bottom")
		(1 "F.Mask" user "Board Geometry/Soldermask Top")
		(3 "B.Mask" user "Board Geometry/Soldermask Bottom")
		(17 "Dwgs.User" user "User.Drawings")
		(19 "Cmts.User" user "User.Comments")
		(21 "Eco1.User" user "User.Eco1")
		(23 "Eco2.User" user "User.Eco2")
		(25 "Edge.Cuts" user "Board Geometry/Outline")
		(27 "Margin" user)
		(31 "F.CrtYd" user "Package Geometry/Place Bound Top")
		(29 "B.CrtYd" user "Package Geometry/Place Bound Bottom")
		(35 "F.Fab" user "Ref Des/Assembly Top")
		(33 "B.Fab" user "Ref Des/Assembly Bottom")
	)
	(footprint ""
		(layer "F.Cu")
		(at 352.663252 -315.66739 90)
		(property "Reference" "PC322"
			(at 0 0 90)
			(layer "F.SilkS")
			(hide yes)
			(effects
				(font
					(size 1.27 1.27)
				)
			)
		)
		(property "Value" ""
			(at 0 0 90)
			(layer "F.Fab")
			(effects
				(font
					(size 1.27 1.27)
				)
			)
		)
		(duplicate_pad_numbers_are_jumpers no)
		(fp_line
			(start 2.750058 0.999998)
			(end -2.750058 0.999998)
			(stroke
				(width 0.1524)
				(type default)
			)
			(layer "F.SilkS")
		)
		(fp_circle
			(center 0 0.999998)
			(end 0 3.750056)
			(stroke
				(width 0.1524)
				(type default)
			)
			(fill no)
			(layer "F.SilkS")
		)
		(fp_poly
			(pts
				(arc
					(start 2.750058 0.999998)
					(mid 0 3.750056)
					(end -2.750058 0.999998)
				)
			)
			(stroke
				(width 0)
				(type default)
			)
			(fill yes)
			(layer "F.SilkS")
		)
		(fp_circle
			(center 0 0.999998)
			(end 0 3.750056)
			(stroke
				(width 0.1)
				(type default)
			)
			(fill no)
			(layer "F.Fab")
		)
		(pad "1" thru_hole rect
			(at 0 0 90)
			(size 1.5748 1.5748)
			(drill 1.0668)
			(layers "*.Cu" "*.Mask")
			(remove_unused_layers no)
			(net "PVCCIN_CPU0")
			(clearance 0)
			(padstack
				(mode front_inner_back)
				(layer "Inner"
					(shape circle)
					(size 1.5748 1.5748)
					(clearance 0)
				)
				(layer "B.Cu"
					(shape rect)
					(size 1.5748 1.5748)
					(clearance 0)
				)
			)
		)
		(pad "2" thru_hole circle
			(at 0 1.999996 90)
			(size 1.5748 1.5748)
			(drill 1.0668)
			(layers "*.Cu" "*.Mask")
			(remove_unused_layers no)
			(net "GND")
			(clearance 0)
		)
	)
)
